FILE_TYPE = CONNECTIVITY;
{Allegro Design Entry HDL 16.6-p007 (v16-6-112F) 10/10/2012}
"PAGE_NUMBER" = 116;
0"NC";
1"SATA6G_RX_DP<3:0>";
2"SATA6G_RX_DN<3:0>";
3"SATA6G_PCH_PCIE_UP_SATA_RXP<7:0>";
4"SATA6G_PCH_PCIE_UP_SATA_RXN<7:0>";
5"SATA6G_PCH_PCIE_UP_SATA_TXP<7:0>";
6"SATA6G_TX_DP<3:0>";
7"SATA6G_PCH_PCIE_UP_SATA_TXN<7:0>";
8"GND\g";
9"GND\g";
10"GND\g";
11"SATA6G_TX_DN<3:0>";
12"PE_PCH_SPRV_RX_C_DP";
13"P3E_PCH_TX_0_DN";
14"P3E_PCH_M2_TX_DP<1>";
15"P2E_SSB_BMC_TX_DN";
16"TP_PCH_RSVD48";
17"A_PCIE_RCOMP_P";
18"A_PCIEUP_RCOMP_N";
19"SATA6G_PCH_PCIE_UP_SATA_TXN<7>";
20"SATA6G_PCH_PCIE_UP_SATA_TXP<7>";
21"P2E_SSB_BMC_TX_C_DP";
22"P2E_SSB_BMC_TX_C_DN";
23"A_EXTCLKP";
24"SATA6G_TX_DN<2>";
25"SATA6G_TX_DP<2>";
26"SATA6G_TX_DN<3>";
27"SATA6G_TX_DP<3>";
28"SATA6G_PCH_PCIE_UP_SATA_TXN<0>";
29"SATA6G_PCH_PCIE_UP_SATA_TXN<1>";
30"SATA6G_PCH_PCIE_UP_SATA_TXN<2>";
31"SATA6G_PCH_PCIE_UP_SATA_TXN<3>";
32"SATA6G_PCH_PCIE_UP_SATA_TXN<4>";
33"SATA6G_PCH_PCIE_UP_SATA_TXN<5>";
34"SATA6G_PCH_PCIE_UP_SATA_TXN<6>";
35"SATA6G_TX_DN<0>";
36"SATA6G_TX_DP<0>";
37"SATA6G_TX_DN<1>";
38"SATA6G_TX_DP<1>";
39"TP_PCH_RSVD52";
40"TP_PCH_RSVD51";
41"TP_PCH_RSVD50";
42"TP_PCH_RSVD49";
43"P2E_SSB_BMC_TX_DP";
44"P3E_PCH_M2_TX_DN<3>";
45"P3E_PCH_M2_TX_DP<2>";
46"P3E_PCH_M2_TX_DN<2>";
47"P3E_PCH_M2_TX_DP<3>";
48"P3E_PCH_TX_0_DP";
49"SATA6G_S1_TX_DP";
50"P3E_PCH_M2_TX_DN<1>";
51"PE_PCH_SPRV_TX_DN";
52"PE_PCH_SPRV_TX_DP";
53"SATA6G_S0_TX_DN";
54"SATA6G_S0_TX_DP";
55"SATA6G_S1_TX_DN";
56"SATA6G_PCH_PCIE_UP_SATA_TXP<2>";
57"SATA6G_PCH_PCIE_UP_SATA_TXP<3>";
58"SATA6G_PCH_PCIE_UP_SATA_TXP<4>";
59"SATA6G_PCH_PCIE_UP_SATA_TXP<5>";
60"SATA6G_PCH_PCIE_UP_SATA_TXP<6>";
61"SATA6G_PCH_PCIE_UP_SATA_TXP<0>";
62"SATA6G_PCH_PCIE_UP_SATA_TXP<1>";
63"A_EXTCLKN";
64"SATA6G_PCH_PCIE_UP_SATA_RXN<7>";
65"SATA6G_PCH_PCIE_UP_SATA_RXP<7>";
66"P2E_SSB_BMC_RX_C_DP";
67"A_PCIEUP_RCOMP_P";
68"SATA6G_RX_DN<2>";
69"SATA6G_RX_DP<2>";
70"SATA6G_RX_DN<3>";
71"SATA6G_RX_DP<3>";
72"SATA6G_PCH_PCIE_UP_SATA_RXN<0>";
73"SATA6G_PCH_PCIE_UP_SATA_RXP<0>";
74"SATA6G_PCH_PCIE_UP_SATA_RXN<1>";
75"SATA6G_PCH_PCIE_UP_SATA_RXP<1>";
76"SATA6G_PCH_PCIE_UP_SATA_RXN<2>";
77"SATA6G_PCH_PCIE_UP_SATA_RXP<2>";
78"SATA6G_PCH_PCIE_UP_SATA_RXN<3>";
79"SATA6G_PCH_PCIE_UP_SATA_RXP<3>";
80"SATA6G_PCH_PCIE_UP_SATA_RXN<4>";
81"SATA6G_PCH_PCIE_UP_SATA_RXP<4>";
82"SATA6G_PCH_PCIE_UP_SATA_RXN<5>";
83"SATA6G_PCH_PCIE_UP_SATA_RXP<5>";
84"SATA6G_PCH_PCIE_UP_SATA_RXN<6>";
85"SATA6G_PCH_PCIE_UP_SATA_RXP<6>";
86"SATA6G_RX_DN<0>";
87"SATA6G_RX_DP<0>";
88"SATA6G_RX_DN<1>";
89"SATA6G_RX_DP<1>";
90"A_PCIE_RCOMP_N";
91"TP_PCH_RSVD47";
92"SATA6G_S1_RX_DN";
93"PE_PCH_SPRV_RX_C_DN";
94"SATA6G_S0_RX_DP";
95"SATA6G_S0_RX_DN";
96"P2E_SSB_BMC_RX_C_DP";
97"P2E_SSB_BMC_RX_C_DN";
98"P3E_PCH_M2_RX_DN<1>";
99"P3E_PCH_RX_0_DP";
100"P3E_PCH_RX_0_DN";
101"P3E_PCH_M2_RX_DN<2>";
102"P3E_PCH_M2_RX_DP<2>";
103"P3E_PCH_M2_RX_DN<3>";
104"P3E_PCH_M2_RX_DP<3>";
105"P3E_PCH_M2_RX_DP<1>";
106"SATA6G_S1_RX_DP";
107"P2E_SSB_BMC_RX_C_DN";
%"RES"
"2","(-7550,2150)","2","mstr_discrete","I108";
;
CDS_SEC"1"
SEC"1"
NO_XNET_CONNECTION"1"
ROOM"SB"
SEC_TYPE"0402"
CDS_LIB"mstr_discrete"
CDS_LOCATION"R3M11"
TOLERANCE"1%"
WATTAGE"1/16W"
MATERIAL"CHIP"
VALUE"100.0"
LOCATION"R3M11"
PART_NUMBER"G21796-017"
PACK_TYPE"0402";
"A"
$PN"1"17;
"B"
$PN"2"90;
%"TAP"
"1","(-1875,3900)","0","mstr_standard","I122";
;
HDL_TAP"TRUE"
BODY_TYPE"PLUMBING"
CDS_LIB"mstr_standard";
"B \NAC \NWC"7;
"S \NAC"
BN"5"33;
%"TAP"
"1","(-1875,3800)","0","mstr_standard","I123";
;
HDL_TAP"TRUE"
BODY_TYPE"PLUMBING"
CDS_LIB"mstr_standard";
"B \NAC \NWC"7;
"S \NAC"
BN"4"32;
%"TAP"
"1","(-2025,4150)","0","mstr_standard","I125";
;
CDS_LIB"mstr_standard"
BODY_TYPE"PLUMBING"
HDL_TAP"TRUE";
"B \NAC \NWC"5;
"S \NAC"
BN"7"20;
%"TAP"
"1","(-2025,4050)","0","mstr_standard","I128";
;
BODY_TYPE"PLUMBING"
HDL_TAP"TRUE"
CDS_LIB"mstr_standard";
"B \NAC \NWC"5;
"S \NAC"
BN"6"60;
%"TAP"
"1","(-1875,4000)","0","mstr_standard","I129";
;
BODY_TYPE"PLUMBING"
HDL_TAP"TRUE"
CDS_LIB"mstr_standard";
"B \NAC \NWC"7;
"S \NAC"
BN"6"34;
%"TAP"
"1","(-1875,4100)","0","mstr_standard","I130";
;
CDS_LIB"mstr_standard"
BODY_TYPE"PLUMBING"
HDL_TAP"TRUE";
"B \NAC \NWC"7;
"S \NAC"
BN"7"19;
%"TAP"
"1","(-1875,3700)","0","mstr_standard","I131";
;
BODY_TYPE"PLUMBING"
CDS_LIB"mstr_standard"
HDL_TAP"TRUE";
"B \NAC \NWC"7;
"S \NAC"
BN"3"31;
%"TAP"
"1","(-1875,3600)","0","mstr_standard","I132";
;
BODY_TYPE"PLUMBING"
CDS_LIB"mstr_standard"
HDL_TAP"TRUE";
"B \NAC \NWC"7;
"S \NAC"
BN"2"30;
%"TAP"
"1","(-1875,3500)","0","mstr_standard","I133";
;
BODY_TYPE"PLUMBING"
HDL_TAP"TRUE"
CDS_LIB"mstr_standard";
"B \NAC \NWC"7;
"S \NAC"
BN"1"29;
%"TAP"
"1","(-1875,3400)","0","mstr_standard","I134";
;
HDL_TAP"TRUE"
BODY_TYPE"PLUMBING"
CDS_LIB"mstr_standard";
"B \NAC \NWC"7;
"S \NAC"
BN"0"28;
%"TAP"
"1","(-2025,3950)","0","mstr_standard","I135";
;
HDL_TAP"TRUE"
BODY_TYPE"PLUMBING"
CDS_LIB"mstr_standard";
"B \NAC \NWC"5;
"S \NAC"
BN"5"59;
%"TAP"
"1","(-2025,3850)","0","mstr_standard","I136";
;
HDL_TAP"TRUE"
BODY_TYPE"PLUMBING"
CDS_LIB"mstr_standard";
"B \NAC \NWC"5;
"S \NAC"
BN"4"58;
%"TAP"
"1","(-2025,3750)","0","mstr_standard","I137";
;
HDL_TAP"TRUE"
BODY_TYPE"PLUMBING"
CDS_LIB"mstr_standard";
"B \NAC \NWC"5;
"S \NAC"
BN"3"57;
%"TAP"
"1","(-2025,3650)","0","mstr_standard","I138";
;
BODY_TYPE"PLUMBING"
CDS_LIB"mstr_standard"
HDL_TAP"TRUE";
"B \NAC \NWC"5;
"S \NAC"
BN"2"56;
%"TAP"
"1","(-2025,3550)","0","mstr_standard","I139";
;
BODY_TYPE"PLUMBING"
CDS_LIB"mstr_standard"
HDL_TAP"TRUE";
"B \NAC \NWC"5;
"S \NAC"
BN"1"62;
%"TAP"
"1","(-2025,3450)","0","mstr_standard","I140";
;
HDL_TAP"TRUE"
BODY_TYPE"PLUMBING"
CDS_LIB"mstr_standard";
"B \NAC \NWC"5;
"S \NAC"
BN"0"61;
%"TAP"
"1","(-6400,3450)","2","mstr_standard","I141";
;
CDS_LIB"mstr_standard"
BODY_TYPE"PLUMBING"
HDL_TAP"TRUE";
"B \NAC \NWC"3;
"S \NAC"
BN"0"73;
%"TAP"
"1","(-6250,3400)","2","mstr_standard","I142";
;
BODY_TYPE"PLUMBING"
CDS_LIB"mstr_standard"
HDL_TAP"TRUE";
"B \NAC \NWC"4;
"S \NAC"
BN"0"72;
%"TAP"
"1","(-6250,3500)","2","mstr_standard","I143";
;
BODY_TYPE"PLUMBING"
CDS_LIB"mstr_standard"
HDL_TAP"TRUE";
"B \NAC \NWC"4;
"S \NAC"
BN"1"74;
%"TAP"
"1","(-6400,3650)","2","mstr_standard","I144";
;
CDS_LIB"mstr_standard"
BODY_TYPE"PLUMBING"
HDL_TAP"TRUE";
"B \NAC \NWC"3;
"S \NAC"
BN"2"77;
%"TAP"
"1","(-6400,3750)","2","mstr_standard","I145";
;
CDS_LIB"mstr_standard"
BODY_TYPE"PLUMBING"
HDL_TAP"TRUE";
"B \NAC \NWC"3;
"S \NAC"
BN"3"79;
%"TAP"
"1","(-6400,3550)","2","mstr_standard","I146";
;
BODY_TYPE"PLUMBING"
CDS_LIB"mstr_standard"
HDL_TAP"TRUE";
"B \NAC \NWC"3;
"S \NAC"
BN"1"75;
%"TAP"
"1","(-6250,3600)","2","mstr_standard","I147";
;
CDS_LIB"mstr_standard"
BODY_TYPE"PLUMBING"
HDL_TAP"TRUE";
"B \NAC \NWC"4;
"S \NAC"
BN"2"76;
%"TAP"
"1","(-6250,3700)","2","mstr_standard","I148";
;
BODY_TYPE"PLUMBING"
CDS_LIB"mstr_standard"
HDL_TAP"TRUE";
"B \NAC \NWC"4;
"S \NAC"
BN"3"78;
%"TAP"
"1","(-6400,3850)","2","mstr_standard","I149";
;
CDS_LIB"mstr_standard"
BODY_TYPE"PLUMBING"
HDL_TAP"TRUE";
"B \NAC \NWC"3;
"S \NAC"
BN"4"81;
%"TAP"
"1","(-6400,3950)","2","mstr_standard","I150";
;
CDS_LIB"mstr_standard"
BODY_TYPE"PLUMBING"
HDL_TAP"TRUE";
"B \NAC \NWC"3;
"S \NAC"
BN"5"83;
%"TAP"
"1","(-6250,4000)","2","mstr_standard","I151";
;
BODY_TYPE"PLUMBING"
CDS_LIB"mstr_standard"
HDL_TAP"TRUE";
"B \NAC \NWC"4;
"S \NAC"
BN"6"84;
%"TAP"
"1","(-6250,3900)","2","mstr_standard","I152";
;
BODY_TYPE"PLUMBING"
CDS_LIB"mstr_standard"
HDL_TAP"TRUE";
"B \NAC \NWC"4;
"S \NAC"
BN"5"82;
%"TAP"
"1","(-6250,3800)","2","mstr_standard","I153";
;
BODY_TYPE"PLUMBING"
CDS_LIB"mstr_standard"
HDL_TAP"TRUE";
"B \NAC \NWC"4;
"S \NAC"
BN"4"80;
%"TAP"
"1","(-6400,4150)","2","mstr_standard","I154";
;
CDS_LIB"mstr_standard"
BODY_TYPE"PLUMBING"
HDL_TAP"TRUE";
"B \NAC \NWC"3;
"S \NAC"
BN"7"65;
%"TAP"
"1","(-6400,4050)","2","mstr_standard","I155";
;
BODY_TYPE"PLUMBING"
CDS_LIB"mstr_standard"
HDL_TAP"TRUE";
"B \NAC \NWC"3;
"S \NAC"
BN"6"85;
%"TAP"
"1","(-6250,4100)","2","mstr_standard","I156";
;
CDS_LIB"mstr_standard"
BODY_TYPE"PLUMBING"
HDL_TAP"TRUE";
"B \NAC \NWC"4;
"S \NAC"
BN"7"64;
%"RES"
"2","(-7125,2150)","2","mstr_discrete","I181";
;
CDS_SEC"1"
CDS_LIB"mstr_discrete"
SEC"1"
CDS_LOCATION"R3M12"
NO_XNET_CONNECTION"1"
ROOM"SB"
SEC_TYPE"0402"
PACK_TYPE"0402"
WATTAGE"1/16W"
LOCATION"R3M12"
MATERIAL"CHIP"
TOLERANCE"1%"
VALUE"100.0"
PART_NUMBER"G21796-017";
"A"
$PN"1"67;
"B"
$PN"2"18;
%"CAP_A"
"2","(-1725,2650)","0","dev_discrete","I182";
;
CDS_SEC"1"
SEC"1"
SEC_TYPE"0402V"
ROOM"SB"
CDS_LIB"dev_discrete"
CDS_LOCATION"C2M4"
LOCATION"C2M4"
MATERIAL"EMPTY"
PART_NUMBER"A36096-030"
VOLTAGE"16V"
TOLERANCE"10%"
VALUE"0.1UF"
PACK_TYPE"0402V";
"A"
$PN"1"43;
"B"
$PN"2"21;
%"CAP_A"
"2","(-1325,2600)","0","dev_discrete","I183";
;
CDS_SEC"1"
ROOM"SB"
SEC"1"
SEC_TYPE"0402V"
CDS_LIB"dev_discrete"
CDS_LOCATION"C2M3"
VALUE"0.1UF"
LOCATION"C2M3"
PART_NUMBER"A36096-030"
VOLTAGE"16V"
TOLERANCE"10%"
MATERIAL"EMPTY"
PACK_TYPE"0402V";
"A"
$PN"1"15;
"B"
$PN"2"22;
%"TAP"
"6","(-6800,3300)","0","mstr_standard","I186";
;
HDL_TAP"TRUE"
CDS_LIB"mstr_standard"
BODY_TYPE"PLUMBING";
"B \NAC \NWC"2;
"S \NAC"
BN"3"70;
%"TAP"
"6","(-6800,3200)","0","mstr_standard","I187";
;
HDL_TAP"TRUE"
CDS_LIB"mstr_standard"
BODY_TYPE"PLUMBING";
"B \NAC \NWC"2;
"S \NAC"
BN"2"68;
%"TAP"
"6","(-6800,3100)","0","mstr_standard","I188";
;
CDS_LIB"mstr_standard"
BODY_TYPE"PLUMBING"
HDL_TAP"TRUE";
"B \NAC \NWC"2;
"S \NAC"
BN"1"88;
%"TAP"
"6","(-6800,3000)","0","mstr_standard","I189";
;
HDL_TAP"TRUE"
BODY_TYPE"PLUMBING"
CDS_LIB"mstr_standard";
"B \NAC \NWC"2;
"S \NAC"
BN"0"86;
%"TAP"
"6","(-6650,3350)","0","mstr_standard","I190";
;
HDL_TAP"TRUE"
CDS_LIB"mstr_standard"
BODY_TYPE"PLUMBING";
"B \NAC \NWC"1;
"S \NAC"
BN"3"71;
%"TAP"
"6","(-6650,3250)","0","mstr_standard","I191";
;
HDL_TAP"TRUE"
CDS_LIB"mstr_standard"
BODY_TYPE"PLUMBING";
"B \NAC \NWC"1;
"S \NAC"
BN"2"69;
%"TAP"
"6","(-6650,3150)","0","mstr_standard","I192";
;
BODY_TYPE"PLUMBING"
CDS_LIB"mstr_standard"
HDL_TAP"TRUE";
"B \NAC \NWC"1;
"S \NAC"
BN"1"89;
%"TAP"
"6","(-6650,3050)","0","mstr_standard","I193";
;
CDS_LIB"mstr_standard"
BODY_TYPE"PLUMBING"
HDL_TAP"TRUE";
"B \NAC \NWC"1;
"S \NAC"
BN"0"87;
%"TAP"
"1","(-1550,3350)","0","mstr_standard","I196";
;
HDL_TAP"TRUE"
CDS_LIB"mstr_standard"
BODY_TYPE"PLUMBING";
"B \NAC \NWC"6;
"S \NAC"
BN"3"27;
%"TAP"
"1","(-1550,3250)","0","mstr_standard","I197";
;
HDL_TAP"TRUE"
BODY_TYPE"PLUMBING"
CDS_LIB"mstr_standard";
"B \NAC \NWC"6;
"S \NAC"
BN"2"25;
%"TAP"
"1","(-1550,3150)","0","mstr_standard","I198";
;
BODY_TYPE"PLUMBING"
CDS_LIB"mstr_standard"
HDL_TAP"TRUE";
"B \NAC \NWC"6;
"S \NAC"
BN"1"38;
%"TAP"
"1","(-1550,3050)","0","mstr_standard","I199";
;
BODY_TYPE"PLUMBING"
CDS_LIB"mstr_standard"
HDL_TAP"TRUE";
"B \NAC \NWC"6;
"S \NAC"
BN"0"36;
%"TAP"
"1","(-1375,3100)","0","mstr_standard","I200";
;
BODY_TYPE"PLUMBING"
CDS_LIB"mstr_standard"
HDL_TAP"TRUE";
"B \NAC \NWC"11;
"S \NAC"
BN"1"37;
%"TAP"
"1","(-1375,3200)","0","mstr_standard","I201";
;
HDL_TAP"TRUE"
BODY_TYPE"PLUMBING"
CDS_LIB"mstr_standard";
"B \NAC \NWC"11;
"S \NAC"
BN"2"24;
%"TAP"
"1","(-1375,3300)","0","mstr_standard","I202";
;
HDL_TAP"TRUE"
BODY_TYPE"PLUMBING"
CDS_LIB"mstr_standard";
"B \NAC \NWC"11;
"S \NAC"
BN"3"26;
%"TAP"
"1","(-1375,3000)","0","mstr_standard","I203";
;
BODY_TYPE"PLUMBING"
HDL_TAP"TRUE"
CDS_LIB"mstr_standard";
"B \NAC \NWC"11;
"S \NAC"
BN"0"35;
%"LBG_CORE_QAT_EXT_D"
"3","(-4025,2850)","0","mstr_u_proc","I220";
;
CDS_SEC"3"
CDS_LIB"mstr_u_proc"
PACK_TYPE"BGA1"
ROOM"SB"
CDS_LOCATION"U7C1"
BOM_COST"SB"
SEC"3"
SEC_TYPE"BGA1"
LOCATION"U7C1"
MATERIAL"IC"
PART_NUMBER"H91415-002";
"USB3_9_PCIE2_TXP"
$PN"BL66"45;
"USB3_9_PCIE2_TXN"
$PN"BK65"46;
"USB3_9_PCIE2_RXP"
$PN"AW69"102;
"USB3_9_PCIE2_RXN"
$PN"AW71"101;
"USB3_8_PCIE1_TXP"
$PN"BR65"14;
"USB3_8_PCIE1_TXN"
$PN"BM65"50;
"USB3_8_PCIE1_RXP"
$PN"AY70"105;
"USB3_8_PCIE1_RXN"
$PN"AY72"98;
"USB3_7_PCIE0_TXP"
$PN"BN63"48;
"USB3_7_PCIE0_TXN"
$PN"BR61"13;
"USB3_7_PCIE0_RXP"
$PN"BA69"99;
"USB3_7_PCIE0_RXN"
$PN"BA71"100;
"USB3_10_PCIE3_GBE_TXP"
$PN"BK61"47;
"USB3_10_PCIE3_GBE_TXN"
$PN"BH61"44;
"USB3_10_PCIE3_GBE_RXP"
$PN"AV70"104;
"USB3_10_PCIE3_GBE_RXN"
$PN"AV72"103;
"RSVD<47>"
$PN"AP69"91;
"RSVD<48>"
$PN"AP71"16;
"RSVD<49>"
$PN"G67"42;
"RSVD<50>"
$PN"H69"41;
"RSVD<51>"
$PN"AA69"40;
"RSVD<52>"
$PN"AA71"39;
"PCIE_RCOMPP"
$PN"BB56"17;
"PCIE_RCOMPN"
$PN"BD58"90;
"PCIEUP_RCOMPP"
$PN"AH58"67;
"PCIEUP_RCOMPN"
$PN"AF58"18;
"PCIE9_SSATA3_TXP"
$PN"AE71"38;
"PCIE9_SSATA3_TXN"
$PN"AE69"37;
"PCIE9_SSATA3_RXP"
$PN"AY66"89;
"PCIE9_SSATA3_RXN"
$PN"AW65"88;
"PCIE8_SSATA2_GBE_TXP"
$PN"AF72"36;
"PCIE8_SSATA2_GBE_TXN"
$PN"AF70"35;
"PCIE8_SSATA2_GBE_RXP"
$PN"BD65"87;
"PCIE8_SSATA2_GBE_RXN"
$PN"BA65"86;
"PCIE7_SSATA1_TXP"
$PN"AH71"49;
"PCIE7_SSATA1_TXN"
$PN"AH69"55;
"PCIE7_SSATA1_RXP"
$PN"BA61"106;
"PCIE7_SSATA1_RXN"
$PN"AY59"92;
"PCIE6_SSATA0_TXP"
$PN"AJ72"54;
"PCIE6_SSATA0_TXN"
$PN"AJ70"53;
"PCIE6_SSATA0_RXP"
$PN"BD61"94;
"PCIE6_SSATA0_RXN"
$PN"BB63"95;
"PCIE5_GBE_TXP"
$PN"BJ63"52;
"PCIE5_GBE_TXN"
$PN"BH65"51;
"PCIE5_GBE_RXP"
$PN"AM71"12;
"PCIE5_GBE_RXN"
$PN"AM69"93;
"PCIE4_GBE_TXP"
$PN"BJ66"43;
"PCIE4_GBE_TXN"
$PN"BG66"15;
"PCIE4_GBE_RXP"
$PN"AN72"96;
"PCIE4_GBE_RXN"
$PN"AN70"97;
"PCIE19_UP7_SATA7_TXP"
$PN"L72"20;
"PCIE19_UP7_SATA7_TXN"
$PN"L70"19;
"PCIE19_UP7_SATA7_RXP"
$PN"AD61"65;
"PCIE19_UP7_SATA7_RXN"
$PN"AA61"64;
"PCIE18_UP6_SATA6_TXP"
$PN"M71"60;
"PCIE18_UP6_SATA6_TXN"
$PN"M69"34;
"PCIE18_UP6_SATA6_RXP"
$PN"AN61"85;
"PCIE18_UP6_SATA6_RXN"
$PN"AP59"84;
"PCIE17_UP5_SATA5_TXP"
$PN"N72"59;
"PCIE17_UP5_SATA5_TXN"
$PN"N70"33;
"PCIE17_UP5_SATA5_RXP"
$PN"AG63"83;
"PCIE17_UP5_SATA5_RXN"
$PN"AH61"82;
"PCIE16_UP4_SATA4_TXP"
$PN"P71"58;
"PCIE16_UP4_SATA4_TXN"
$PN"P69"32;
"PCIE16_UP4_SATA4_RXP"
$PN"AH65"81;
"PCIE16_UP4_SATA4_RXN"
$PN"AF65"80;
"PCIE15_UP3_SATA3_TXP"
$PN"R72"57;
"PCIE15_UP3_SATA3_TXN"
$PN"R70"31;
"PCIE15_UP3_SATA3_RXP"
$PN"AL63"79;
"PCIE15_UP3_SATA3_RXN"
$PN"AP63"78;
"PCIE14_UP2_SATA2_TXP"
$PN"T71"56;
"PCIE14_UP2_SATA2_TXN"
$PN"T69"30;
"PCIE14_UP2_SATA2_RXP"
$PN"AJ63"77;
"PCIE14_UP2_SATA2_RXN"
$PN"AK65"76;
"PCIE13_UP1_SATA1_TXP"
$PN"V72"62;
"PCIE13_UP1_SATA1_TXN"
$PN"V70"29;
"PCIE13_UP1_SATA1_RXP"
$PN"AN65"75;
"PCIE13_UP1_SATA1_RXN"
$PN"AL66"74;
"PCIE12_UP0_SATA0_TXP"
$PN"W71"61;
"PCIE12_UP0_SATA0_TXN"
$PN"W69"28;
"PCIE12_UP0_SATA0_RXP"
$PN"AT63"73;
"PCIE12_UP0_SATA0_RXN"
$PN"AR61"72;
"PCIE11_SSATA5_GBE_TXP"
$PN"AC71"27;
"PCIE11_SSATA5_GBE_TXN"
$PN"AC69"26;
"PCIE11_SSATA5_GBE_RXP"
$PN"AV66"71;
"PCIE11_SSATA5_GBE_RXN"
$PN"AT66"70;
"PCIE10_SSATA4_TXP"
$PN"AD72"25;
"PCIE10_SSATA4_TXN"
$PN"AD70"24;
"PCIE10_SSATA4_RXP"
$PN"AU65"69;
"PCIE10_SSATA4_RXN"
$PN"AV63"68;
"EXTCLKP"
$PN"E67"23;
"EXTCLKN"
$PN"D66"63;
%"RES"
"2","(-2125,1400)","0","mstr_discrete","I229";
;
CDS_SEC"1"
ROOM"SB"
SEC"1"
SEC_TYPE"0402"
CDS_LOCATION"R7B8"
CDS_LIB"mstr_discrete"
PART_NUMBER"G21796-016"
WATTAGE"1/16W"
PACK_TYPE"0402"
TOLERANCE"1%"
VALUE"10.0K"
LOCATION"R7B8"
MATERIAL"EMPTY";
"A"
$PN"1"63;
"B"
$PN"2"8;
%"RES"
"2","(-1825,1400)","0","mstr_discrete","I230";
;
CDS_SEC"1"
SEC_TYPE"0402"
SEC"1"
ROOM"SB"
CDS_LOCATION"R7B7"
CDS_LIB"mstr_discrete"
WATTAGE"1/16W"
VALUE"10.0K"
PART_NUMBER"G21796-016"
LOCATION"R7B7"
MATERIAL"EMPTY"
TOLERANCE"1%"
PACK_TYPE"0402";
"A"
$PN"1"23;
"B"
$PN"2"8;
%"GND"
"1","(-1925,1000)","0","mstr_symbols","I231";
;
HDL_POWER"GND"
CDS_LIB"mstr_symbols"
SIZE"1B"
BODY_TYPE"PLUMBING"
VOLTAGE"0.0V";
"A\NAC"8;
%"RES"
"2","(-6225,725)","0","mstr_discrete","I234";
;
CDS_LOCATION"R3M9"
$SEC"1"
CDS_SEC"1"
ROOM"SB"
CDS_LIB"mstr_discrete"
WATTAGE"1/16W"
MATERIAL"CHIP"
PACK_TYPE"0402"
TOLERANCE"1%"
VALUE"100.0K"
PART_NUMBER"G21796-010"
LOCATION"R3M9";
"A"
$PN"1"107;
"B"
$PN"2"9;
%"RES"
"2","(-5900,725)","0","mstr_discrete","I235";
;
CDS_SEC"1"
ROOM"SB"
$SEC"1"
CDS_LOCATION"R3M8"
CDS_LIB"mstr_discrete"
PART_NUMBER"G21796-010"
TOLERANCE"1%"
PACK_TYPE"0402"
LOCATION"R3M8"
VALUE"100.0K"
WATTAGE"1/16W"
MATERIAL"CHIP";
"A"
$PN"1"66;
"B"
$PN"2"10;
%"GND"
"1","(-6225,400)","0","mstr_symbols","I236";
;
HDL_POWER"GND"
SIZE"1B"
CDS_LIB"mstr_symbols"
BODY_TYPE"PLUMBING"
VOLTAGE"0.0V";
"A\NAC"9;
%"GND"
"1","(-5900,400)","0","mstr_symbols","I237";
;
HDL_POWER"GND"
SIZE"1B"
CDS_LIB"mstr_symbols"
BODY_TYPE"PLUMBING"
VOLTAGE"0.0V";
"A\NAC"10;
END.
